FILE_TYPE = MULTI_PHYS_TABLE;

PART 'TPS3808G18DBVR'

{========================================================================================}
:VALUE            | PART_TYPE | MATERIAL | PART_NUMBER      = PART_NUMBER   | JEDEC_TYPE  | DESCRIPTION                           | MANUFTR | MANUF_PN         | RD_CMPLS_LVL | CMPLS_LVL | FROM_PJ         | CLASS | DIP_SMD | DATA                  | EE_CHECK_LIST | FP_ECN | PSL | LIFECYCLE      | CREATOR | STANDARD | CREATEDAY  | STATUS ;
{========================================================================================}
 'TPS3808G18DBVR' | 'SMLF'    | 'IC'     | 'AL003808003'(!) = 'AL003808003' |'SOT23-6'| 'IC OTHER(6P) TPS3808G18DBVR(SOT-23)' | 'TIC'   | 'TPS3808G18DBVR' | 'EP'         | ''        | 'S1B-ALLEN'     | 'IC'  | ''      | 'TPS3808.pdf'         | ''            | ''     | ''  | ''               | ''      | ''       | '20120327' | ''    
 'TPS3808G18DBVR' | 'SMLF'    | 'EMPTY'  | 'AL003808003'(!) = 'AL003808003' |'SOT23-6'| 'IC OTHER(6P) TPS3808G18DBVR(SOT-23)' | 'TIC'   | 'TPS3808G18DBVR' | 'EP'         | ''        | 'S1B-ALLEN'     | 'IC'  | ''      | 'TPS3808.pdf'         | ''            | ''     | ''  | ''               | ''      | ''       | '20120327' | ''    
 'TPS3808G01DBVR' | 'SMLF'    | 'IC'     | 'AL003808005'(!) = 'AL003808005' |'SOT23-6XD'| 'IC OTHER(6P)TPS3808G01DBVR(SOT23)'   | 'TIC'   | 'TPS3808G01DBVR' | 'EP(V1)'     | 'EP(V1)'  | 'T2B-JHIH-RONG' | 'IC'  | ''      | 'TPS3808_REV2008.pdf' | ''            | ''     | ''  | ''               | ''      | ''       | '20120327' | ''    
 'TPS3808G01DBVR' | 'SMLF'    | 'EMPTY'  | 'AL003808005'(!) = 'AL003808005' |'SOT23-6XD'| 'IC OTHER(6P)TPS3808G01DBVR(SOT23)'   | 'TIC'   | 'TPS3808G01DBVR' | 'EP(V1)'     | 'EP(V1)'  | 'T2B-JHIH-RONG' | 'IC'  | ''      | 'TPS3808_REV2008.pdf' | ''            | ''     | ''  | ''               | ''      | ''       | '20120327' | ''    

END_PART

END.

